(kicad_pcb
	(version 20260206)
	(generator "pcbnew")
	(generator_version "10.0")
	(general
		(thickness 1.6)
		(legacy_teardrops no)
	)
	(paper "A4")
	(title_block
		(title "12092022_DA0F0TMDCD0_F0T_Management_Board_D_brd_V3_OCP.brd")
		(comment 1 "Grand Teton / footprints 822-825 of 1440")
	)
	(layers
		(0 "F.Cu" signal "TOP")
		(4 "In1.Cu" signal "GND")
		(6 "In2.Cu" signal "IN1")
		(8 "In3.Cu" signal "GND1")
		(10 "In4.Cu" signal "IN2")
		(12 "In5.Cu" signal "VCC")
		(14 "In6.Cu" signal "VCC1")
		(16 "In7.Cu" signal "IN3")
		(18 "In8.Cu" signal "GND2")
		(20 "In9.Cu" signal "IN4")
		(22 "In10.Cu" signal "GND3")
		(2 "B.Cu" signal "BOTTOM")
		(9 "F.Adhes" user "F.Adhesive")
		(11 "B.Adhes" user "B.Adhesive")
		(13 "F.Paste" user "Package Geometry/Pastemask Top")
		(15 "B.Paste" user "Package Geometry/Pastemask Bottom")
		(5 "F.SilkS" user "Ref Des/Silkscreen Top")
		(7 "B.SilkS" user "Ref Des/Silkscreen Bottom")
		(1 "F.Mask" user "Board Geometry/Soldermask Top")
		(3 "B.Mask" user "Board Geometry/Soldermask Bottom")
		(17 "Dwgs.User" user "User.Drawings")
		(19 "Cmts.User" user "User.Comments")
		(21 "Eco1.User" user "User.Eco1")
		(23 "Eco2.User" user "User.Eco2")
		(25 "Edge.Cuts" user "Board Geometry/Outline")
		(27 "Margin" user)
		(31 "F.CrtYd" user "Package Geometry/Place Bound Top")
		(29 "B.CrtYd" user "Package Geometry/Place Bound Bottom")
		(35 "F.Fab" user "Ref Des/Assembly Top")
		(33 "B.Fab" user "Ref Des/Assembly Bottom")
	)
	(footprint ""
		(layer "B.Cu")
		(at 79.57947 -54.898798)
		(property "Reference" "C221"
			(at 0 0 0)
			(layer "B.SilkS")
			(hide yes)
			(effects
				(font
					(size 1.27 1.27)
				)
				(justify mirror)
			)
		)
		(property "Value" ""
			(at 0 0 0)
			(layer "B.Fab")
			(effects
				(font
					(size 1.27 1.27)
				)
				(justify mirror)
			)
		)
		(duplicate_pad_numbers_are_jumpers no)
		(fp_line
			(start -0.7874 -0.4064)
			(end -0.7874 0.4064)
			(stroke
				(width 0.1524)
				(type default)
			)
			(layer "B.SilkS")
		)
		(fp_line
			(start -0.7874 0.4064)
			(end 0.7874 0.4064)
			(stroke
				(width 0.1524)
				(type default)
			)
			(layer "B.SilkS")
		)
		(fp_line
			(start 0.7874 -0.4064)
			(end -0.7874 -0.4064)
			(stroke
				(width 0.1524)
				(type default)
			)
			(layer "B.SilkS")
		)
		(fp_line
			(start 0.7874 0.4064)
			(end 0.7874 -0.4064)
			(stroke
				(width 0.1524)
				(type default)
			)
			(layer "B.SilkS")
		)
		(fp_line
			(start -0.67945 -0.3048)
			(end -0.67945 0.3048)
			(stroke
				(width 0.1)
				(type default)
			)
			(layer "B.Fab")
		)
		(fp_line
			(start -0.67945 0.3048)
			(end -0.120396 0.3048)
			(stroke
				(width 0.1)
				(type default)
			)
			(layer "B.Fab")
		)
		(fp_line
			(start -0.12065 -0.3048)
			(end -0.67945 -0.3048)
			(stroke
				(width 0.1)
				(type default)
			)
			(layer "B.Fab")
		)
		(fp_line
			(start -0.12065 -0.2794)
			(end -0.12065 -0.3048)
			(stroke
				(width 0.1)
				(type default)
			)
			(layer "B.Fab")
		)
		(fp_line
			(start -0.120396 0.2794)
			(end 0.12065 0.2794)
			(stroke
				(width 0.1)
				(type default)
			)
			(layer "B.Fab")
		)
		(fp_line
			(start -0.120396 0.3048)
			(end -0.120396 0.2794)
			(stroke
				(width 0.1)
				(type default)
			)
			(layer "B.Fab")
		)
		(fp_line
			(start 0.12065 -0.305054)
			(end 0.12065 -0.2794)
			(stroke
				(width 0.1)
				(type default)
			)
			(layer "B.Fab")
		)
		(fp_line
			(start 0.12065 -0.2794)
			(end -0.12065 -0.2794)
			(stroke
				(width 0.1)
				(type default)
			)
			(layer "B.Fab")
		)
		(fp_line
			(start 0.12065 0.2794)
			(end 0.12065 0.3048)
			(stroke
				(width 0.1)
				(type default)
			)
			(layer "B.Fab")
		)
		(fp_line
			(start 0.12065 0.3048)
			(end 0.67945 0.3048)
			(stroke
				(width 0.1)
				(type default)
			)
			(layer "B.Fab")
		)
		(fp_line
			(start 0.67945 -0.305054)
			(end 0.12065 -0.305054)
			(stroke
				(width 0.1)
				(type default)
			)
			(layer "B.Fab")
		)
		(fp_line
			(start 0.67945 0.3048)
			(end 0.67945 -0.305054)
			(stroke
				(width 0.1)
				(type default)
			)
			(layer "B.Fab")
		)
		(pad "1" smd circle
			(at 0.40005 0 180)
			(size 0 0)
			(layers "B.Cu" "B.Mask" "B.Paste")
			(net "P1V2_AUX")
		)
		(pad "2" smd circle
			(at -0.40005 0 180)
			(size 0 0)
			(layers "B.Cu" "B.Mask" "B.Paste")
			(net "GND")
		)
	)
	(footprint ""
		(layer "B.Cu")
		(at 76.239878 -55.895748 -90)
		(property "Reference" "C123"
			(at 0 0 90)
			(layer "B.SilkS")
			(hide yes)
			(effects
				(font
					(size 1.27 1.27)
				)
				(justify mirror)
			)
		)
		(property "Value" ""
			(at 0 0 90)
			(layer "B.Fab")
			(effects
				(font
					(size 1.27 1.27)
				)
				(justify mirror)
			)
		)
		(duplicate_pad_numbers_are_jumpers no)
		(fp_line
			(start -1.2954 0.5842)
			(end 1.2954 0.5842)
			(stroke
				(width 0.1524)
				(type default)
			)
			(layer "B.SilkS")
		)
		(fp_line
			(start 1.2954 0.5842)
			(end 1.2954 -0.5842)
			(stroke
				(width 0.1524)
				(type default)
			)
			(layer "B.SilkS")
		)
		(fp_line
			(start -1.2954 -0.5842)
			(end -1.2954 0.5842)
			(stroke
				(width 0.1524)
				(type default)
			)
			(layer "B.SilkS")
		)
		(fp_line
			(start 0 -0.5842)
			(end 0 0.5842)
			(stroke
				(width 0.1524)
				(type default)
			)
			(layer "B.SilkS")
		)
		(fp_line
			(start 1.2954 -0.5842)
			(end -1.2954 -0.5842)
			(stroke
				(width 0.1524)
				(type default)
			)
			(layer "B.SilkS")
		)
		(fp_line
			(start -0.8636 0.4572)
			(end 0.8636 0.4572)
			(stroke
				(width 0.1)
				(type default)
			)
			(layer "B.Fab")
		)
		(fp_line
			(start 0.8636 0.4572)
			(end 0.8636 0.4064)
			(stroke
				(width 0.1)
				(type default)
			)
			(layer "B.Fab")
		)
		(fp_line
			(start -1.1938 0.4064)
			(end -0.8636 0.4064)
			(stroke
				(width 0.1)
				(type default)
			)
			(layer "B.Fab")
		)
		(fp_line
			(start -0.8636 0.4064)
			(end -0.8636 0.4572)
			(stroke
				(width 0.1)
				(type default)
			)
			(layer "B.Fab")
		)
		(fp_line
			(start 0.8636 0.4064)
			(end 1.1938 0.4064)
			(stroke
				(width 0.1)
				(type default)
			)
			(layer "B.Fab")
		)
		(fp_line
			(start 1.1938 0.4064)
			(end 1.1938 -0.4064)
			(stroke
				(width 0.1)
				(type default)
			)
			(layer "B.Fab")
		)
		(fp_line
			(start -1.1938 -0.4064)
			(end -1.1938 0.4064)
			(stroke
				(width 0.1)
				(type default)
			)
			(layer "B.Fab")
		)
		(fp_line
			(start -0.8636 -0.4064)
			(end -1.1938 -0.4064)
			(stroke
				(width 0.1)
				(type default)
			)
			(layer "B.Fab")
		)
		(fp_line
			(start 0.8636 -0.4064)
			(end 0.8636 -0.4572)
			(stroke
				(width 0.1)
				(type default)
			)
			(layer "B.Fab")
		)
		(fp_line
			(start 1.1938 -0.4064)
			(end 0.8636 -0.4064)
			(stroke
				(width 0.1)
				(type default)
			)
			(layer "B.Fab")
		)
		(fp_line
			(start -0.8636 -0.4572)
			(end -0.8636 -0.4064)
			(stroke
				(width 0.1)
				(type default)
			)
			(layer "B.Fab")
		)
		(fp_line
			(start 0.8636 -0.4572)
			(end -0.8636 -0.4572)
			(stroke
				(width 0.1)
				(type default)
			)
			(layer "B.Fab")
		)
		(pad "1" smd rect
			(at 0.7366 0 180)
			(size 0.7112 0.8128)
			(layers "B.Cu" "B.Mask" "B.Paste")
			(net "P1V0_AUX")
		)
		(pad "2" smd rect
			(at -0.7366 0 180)
			(size 0.7112 0.8128)
			(layers "B.Cu" "B.Mask" "B.Paste")
			(net "GND")
		)
	)
	(footprint ""
		(layer "B.Cu")
		(at 59.309 -24.257 -90)
		(property "Reference" "C148"
			(at 0 0 90)
			(layer "B.SilkS")
			(hide yes)
			(effects
				(font
					(size 1.27 1.27)
				)
				(justify mirror)
			)
		)
		(property "Value" ""
			(at 0 0 90)
			(layer "B.Fab")
			(effects
				(font
					(size 1.27 1.27)
				)
				(justify mirror)
			)
		)
		(duplicate_pad_numbers_are_jumpers no)
		(fp_line
			(start -0.7874 0.4064)
			(end 0.7874 0.4064)
			(stroke
				(width 0.1524)
				(type default)
			)
			(layer "B.SilkS")
		)
		(fp_line
			(start 0.7874 0.4064)
			(end 0.7874 -0.4064)
			(stroke
				(width 0.1524)
				(type default)
			)
			(layer "B.SilkS")
		)
		(fp_line
			(start -0.7874 -0.4064)
			(end -0.7874 0.4064)
			(stroke
				(width 0.1524)
				(type default)
			)
			(layer "B.SilkS")
		)
		(fp_line
			(start 0.7874 -0.4064)
			(end -0.7874 -0.4064)
			(stroke
				(width 0.1524)
				(type default)
			)
			(layer "B.SilkS")
		)
		(fp_line
			(start -0.67945 0.3048)
			(end -0.120396 0.3048)
			(stroke
				(width 0.1)
				(type default)
			)
			(layer "B.Fab")
		)
		(fp_line
			(start -0.120396 0.3048)
			(end -0.120396 0.2794)
			(stroke
				(width 0.1)
				(type default)
			)
			(layer "B.Fab")
		)
		(fp_line
			(start 0.12065 0.3048)
			(end 0.67945 0.3048)
			(stroke
				(width 0.1)
				(type default)
			)
			(layer "B.Fab")
		)
		(fp_line
			(start 0.67945 0.3048)
			(end 0.67945 -0.305054)
			(stroke
				(width 0.1)
				(type default)
			)
			(layer "B.Fab")
		)
		(fp_line
			(start -0.120396 0.2794)
			(end 0.12065 0.2794)
			(stroke
				(width 0.1)
				(type default)
			)
			(layer "B.Fab")
		)
		(fp_line
			(start 0.12065 0.2794)
			(end 0.12065 0.3048)
			(stroke
				(width 0.1)
				(type default)
			)
			(layer "B.Fab")
		)
		(fp_line
			(start -0.12065 -0.2794)
			(end -0.12065 -0.3048)
			(stroke
				(width 0.1)
				(type default)
			)
			(layer "B.Fab")
		)
		(fp_line
			(start 0.12065 -0.2794)
			(end -0.12065 -0.2794)
			(stroke
				(width 0.1)
				(type default)
			)
			(layer "B.Fab")
		)
		(fp_line
			(start -0.67945 -0.3048)
			(end -0.67945 0.3048)
			(stroke
				(width 0.1)
				(type default)
			)
			(layer "B.Fab")
		)
		(fp_line
			(start -0.12065 -0.3048)
			(end -0.67945 -0.3048)
			(stroke
				(width 0.1)
				(type default)
			)
			(layer "B.Fab")
		)
		(fp_line
			(start 0.12065 -0.305054)
			(end 0.12065 -0.2794)
			(stroke
				(width 0.1)
				(type default)
			)
			(layer "B.Fab")
		)
		(fp_line
			(start 0.67945 -0.305054)
			(end 0.12065 -0.305054)
			(stroke
				(width 0.1)
				(type default)
			)
			(layer "B.Fab")
		)
		(pad "1" smd circle
			(at 0.40005 0 90)
			(size 0 0)
			(layers "B.Cu" "B.Mask" "B.Paste")
			(net "P3V3_AUX")
		)
		(pad "2" smd circle
			(at -0.40005 0 90)
			(size 0 0)
			(layers "B.Cu" "B.Mask" "B.Paste")
			(net "GND")
		)
	)
	(footprint ""
		(layer "B.Cu")
		(at 64.102996 -34.637726 -90)
		(property "Reference" "R210"
			(at 0 0 90)
			(layer "B.SilkS")
			(hide yes)
			(effects
				(font
					(size 1.27 1.27)
				)
				(justify mirror)
			)
		)
		(property "Value" ""
			(at 0 0 90)
			(layer "B.Fab")
			(effects
				(font
					(size 1.27 1.27)
				)
				(justify mirror)
			)
		)
		(duplicate_pad_numbers_are_jumpers no)
		(fp_line
			(start -0.7874 0.4064)
			(end 0.7874 0.4064)
			(stroke
				(width 0.1524)
				(type default)
			)
			(layer "B.SilkS")
		)
		(fp_line
			(start 0.7874 0.4064)
			(end 0.7874 -0.4064)
			(stroke
				(width 0.1524)
				(type default)
			)
			(layer "B.SilkS")
		)
		(fp_line
			(start -0.7874 -0.4064)
			(end -0.7874 0.4064)
			(stroke
				(width 0.1524)
				(type default)
			)
			(layer "B.SilkS")
		)
		(fp_line
			(start 0.7874 -0.4064)
			(end -0.7874 -0.4064)
			(stroke
				(width 0.1524)
				(type default)
			)
			(layer "B.SilkS")
		)
		(fp_line
			(start -0.67945 0.3048)
			(end -0.120396 0.3048)
			(stroke
				(width 0.1)
				(type default)
			)
			(layer "B.Fab")
		)
		(fp_line
			(start -0.120396 0.3048)
			(end -0.120396 0.2794)
			(stroke
				(width 0.1)
				(type default)
			)
			(layer "B.Fab")
		)
		(fp_line
			(start 0.12065 0.3048)
			(end 0.67945 0.3048)
			(stroke
				(width 0.1)
				(type default)
			)
			(layer "B.Fab")
		)
		(fp_line
			(start 0.67945 0.3048)
			(end 0.67945 -0.305054)
			(stroke
				(width 0.1)
				(type default)
			)
			(layer "B.Fab")
		)
		(fp_line
			(start -0.120396 0.2794)
			(end 0.12065 0.2794)
			(stroke
				(width 0.1)
				(type default)
			)
			(layer "B.Fab")
		)
		(fp_line
			(start 0.12065 0.2794)
			(end 0.12065 0.3048)
			(stroke
				(width 0.1)
				(type default)
			)
			(layer "B.Fab")
		)
		(fp_line
			(start -0.12065 -0.2794)
			(end -0.12065 -0.3048)
			(stroke
				(width 0.1)
				(type default)
			)
			(layer "B.Fab")
		)
		(fp_line
			(start 0.12065 -0.2794)
			(end -0.12065 -0.2794)
			(stroke
				(width 0.1)
				(type default)
			)
			(layer "B.Fab")
		)
		(fp_line
			(start -0.67945 -0.3048)
			(end -0.67945 0.3048)
			(stroke
				(width 0.1)
				(type default)
			)
			(layer "B.Fab")
		)
		(fp_line
			(start -0.12065 -0.3048)
			(end -0.67945 -0.3048)
			(stroke
				(width 0.1)
				(type default)
			)
			(layer "B.Fab")
		)
		(fp_line
			(start 0.12065 -0.305054)
			(end 0.12065 -0.2794)
			(stroke
				(width 0.1)
				(type default)
			)
			(layer "B.Fab")
		)
		(fp_line
			(start 0.67945 -0.305054)
			(end 0.12065 -0.305054)
			(stroke
				(width 0.1)
				(type default)
			)
			(layer "B.Fab")
		)
		(pad "1" smd circle
			(at 0.40005 0 90)
			(size 0 0)
			(layers "B.Cu" "B.Mask" "B.Paste")
			(net "GND")
		)
		(pad "2" smd circle
			(at -0.40005 0 90)
			(size 0 0)
			(layers "B.Cu" "B.Mask" "B.Paste")
			(net "PD_SP_ENTEST")
		)
	)
)
